(kicad_sch
	(version 20250114)
	(generator "eeschema")
	(generator_version "9.0")
	(paper "A3")
	(title_block
		(title "Kintex 410T devboard")
		(date "2024-04-03")
		(rev "1.1.2")
	)
	(text "Main system clock"
		(exclude_from_sim no)
		(at 12.7 15.24 0)
		(effects
			(font
				(size 1.27 1.27)
				(thickness 0.254)
				(bold yes)
			)
			(justify left bottom)
		)
	)
	(text "PLL"
		(exclude_from_sim no)
		(at 12.7 138.43 0)
		(effects
			(font
				(size 1.27 1.27)
				(thickness 0.254)
				(bold yes)
			)
			(justify left bottom)
		)
	)
	(junction
		(at 176.53 176.53)
		(diameter 0)
		(color 0 0 0 0)
	)
	(junction
		(at 265.43 176.53)
		(diameter 0)
		(color 0 0 0 0)
	)
	(junction
		(at 187.96 186.69)
		(diameter 0)
		(color 0 0 0 0)
	)
	(junction
		(at 176.53 186.69)
		(diameter 0)
		(color 0 0 0 0)
	)
	(junction
		(at 200.66 60.96)
		(diameter 0)
		(color 0 0 0 0)
	)
	(junction
		(at 234.95 190.5)
		(diameter 0)
		(color 0 0 0 0)
	)
	(junction
		(at 185.42 210.82)
		(diameter 0)
		(color 0 0 0 0)
	)
	(junction
		(at 165.1 210.82)
		(diameter 0)
		(color 0 0 0 0)
	)
	(junction
		(at 198.12 176.53)
		(diameter 0)
		(color 0 0 0 0)
	)
	(junction
		(at 255.27 176.53)
		(diameter 0)
		(color 0 0 0 0)
	)
	(junction
		(at 242.57 73.66)
		(diameter 0)
		(color 0 0 0 0)
	)
	(junction
		(at 255.27 186.69)
		(diameter 0)
		(color 0 0 0 0)
	)
	(junction
		(at 242.57 81.28)
		(diameter 0)
		(color 0 0 0 0)
	)
	(junction
		(at 200.66 78.74)
		(diameter 0)
		(color 0 0 0 0)
	)
	(junction
		(at 265.43 186.69)
		(diameter 0)
		(color 0 0 0 0)
	)
	(junction
		(at 243.84 176.53)
		(diameter 0)
		(color 0 0 0 0)
	)
	(junction
		(at 187.96 176.53)
		(diameter 0)
		(color 0 0 0 0)
	)
	(no_connect
		(at 233.68 203.2)
	)
	(no_connect
		(at 233.68 205.74)
	)
	(no_connect
		(at 208.28 198.12)
	)
	(no_connect
		(at 233.68 210.82)
	)
	(bus_entry
		(at 284.48 208.28)
		(size 1.27 -1.27)
		(stroke
			(width 0)
			(type default)
		)
	)
	(bus_entry
		(at 267.97 76.2)
		(size -2.54 2.54)
		(stroke
			(width 0)
			(type default)
		)
	)
	(bus_entry
		(at 196.85 209.55)
		(size 1.27 -1.27)
		(stroke
			(width 0)
			(type default)
		)
	)
	(bus_entry
		(at 196.85 212.09)
		(size 1.27 -1.27)
		(stroke
			(width 0)
			(type default)
		)
	)
	(bus_entry
		(at 187.96 195.58)
		(size 1.27 0)
		(stroke
			(width 0)
			(type default)
		)
	)
	(bus_entry
		(at 267.97 73.66)
		(size -2.54 2.54)
		(stroke
			(width 0)
			(type default)
		)
	)
	(bus_entry
		(at 284.48 198.12)
		(size 1.27 -1.27)
		(stroke
			(width 0)
			(type default)
		)
	)
	(bus_entry
		(at 284.48 200.66)
		(size 1.27 -1.27)
		(stroke
			(width 0)
			(type default)
		)
	)
	(wire
		(pts
			(xy 171.45 210.82) (xy 165.1 210.82)
		)
		(stroke
			(width 0)
			(type default)
		)
	)
	(wire
		(pts
			(xy 322.58 226.06) (xy 322.58 228.6)
		)
		(stroke
			(width 0)
			(type default)
		)
	)
	(wire
		(pts
			(xy 265.43 186.69) (xy 255.27 186.69)
		)
		(stroke
			(width 0)
			(type default)
		)
	)
	(wire
		(pts
			(xy 185.42 204.47) (xy 185.42 210.82)
		)
		(stroke
			(width 0)
			(type default)
		)
	)
	(wire
		(pts
			(xy 265.43 184.15) (xy 265.43 186.69)
		)
		(stroke
			(width 0)
			(type default)
		)
	)
	(wire
		(pts
			(xy 234.95 176.53) (xy 243.84 176.53)
		)
		(stroke
			(width 0)
			(type default)
		)
	)
	(wire
		(pts
			(xy 185.42 210.82) (xy 179.07 210.82)
		)
		(stroke
			(width 0)
			(type default)
		)
	)
	(wire
		(pts
			(xy 153.67 176.53) (xy 153.67 170.18)
		)
		(stroke
			(width 0)
			(type default)
		)
	)
	(wire
		(pts
			(xy 233.68 198.12) (xy 257.81 198.12)
		)
		(stroke
			(width 0)
			(type default)
		)
	)
	(wire
		(pts
			(xy 220.98 215.9) (xy 220.98 222.25)
		)
		(stroke
			(width 0)
			(type default)
		)
	)
	(bus
		(pts
			(xy 198.12 228.6) (xy 196.85 227.33)
		)
		(stroke
			(width 0)
			(type default)
		)
	)
	(wire
		(pts
			(xy 243.84 176.53) (xy 255.27 176.53)
		)
		(stroke
			(width 0)
			(type default)
		)
	)
	(wire
		(pts
			(xy 252.73 73.66) (xy 252.73 76.2)
		)
		(stroke
			(width 0)
			(type default)
		)
	)
	(wire
		(pts
			(xy 265.43 175.26) (xy 265.43 176.53)
		)
		(stroke
			(width 0)
			(type default)
		)
	)
	(bus
		(pts
			(xy 287.02 194.31) (xy 285.75 195.58)
		)
		(stroke
			(width 0)
			(type default)
		)
	)
	(wire
		(pts
			(xy 175.26 215.9) (xy 175.26 222.25)
		)
		(stroke
			(width 0)
			(type default)
		)
	)
	(bus
		(pts
			(xy 290.83 194.31) (xy 287.02 194.31)
		)
		(stroke
			(width 0)
			(type default)
		)
	)
	(wire
		(pts
			(xy 176.53 186.69) (xy 176.53 187.96)
		)
		(stroke
			(width 0)
			(type default)
		)
	)
	(wire
		(pts
			(xy 176.53 186.69) (xy 187.96 186.69)
		)
		(stroke
			(width 0)
			(type default)
		)
	)
	(wire
		(pts
			(xy 262.89 208.28) (xy 284.48 208.28)
		)
		(stroke
			(width 0)
			(type default)
		)
	)
	(wire
		(pts
			(xy 252.73 81.28) (xy 252.73 78.74)
		)
		(stroke
			(width 0)
			(type default)
		)
	)
	(bus
		(pts
			(xy 196.85 209.55) (xy 196.85 212.09)
		)
		(stroke
			(width 0)
			(type default)
		)
	)
	(wire
		(pts
			(xy 209.55 81.28) (xy 212.09 81.28)
		)
		(stroke
			(width 0)
			(type default)
		)
	)
	(wire
		(pts
			(xy 255.27 186.69) (xy 243.84 186.69)
		)
		(stroke
			(width 0)
			(type default)
		)
	)
	(wire
		(pts
			(xy 233.68 76.2) (xy 233.68 73.66)
		)
		(stroke
			(width 0)
			(type default)
		)
	)
	(wire
		(pts
			(xy 185.42 210.82) (xy 185.42 214.63)
		)
		(stroke
			(width 0)
			(type default)
		)
	)
	(wire
		(pts
			(xy 233.68 73.66) (xy 242.57 73.66)
		)
		(stroke
			(width 0)
			(type default)
		)
	)
	(wire
		(pts
			(xy 165.1 219.71) (xy 165.1 222.25)
		)
		(stroke
			(width 0)
			(type default)
		)
	)
	(wire
		(pts
			(xy 328.93 219.71) (xy 342.265 219.71)
		)
		(stroke
			(width 0)
			(type default)
		)
	)
	(bus
		(pts
			(xy 269.24 71.12) (xy 267.97 72.39)
		)
		(stroke
			(width 0)
			(type default)
		)
	)
	(wire
		(pts
			(xy 233.68 208.28) (xy 257.81 208.28)
		)
		(stroke
			(width 0)
			(type default)
		)
	)
	(wire
		(pts
			(xy 165.1 201.93) (xy 208.28 201.93)
		)
		(stroke
			(width 0)
			(type default)
		)
	)
	(wire
		(pts
			(xy 255.27 184.15) (xy 255.27 186.69)
		)
		(stroke
			(width 0)
			(type default)
		)
	)
	(wire
		(pts
			(xy 255.27 176.53) (xy 255.27 179.07)
		)
		(stroke
			(width 0)
			(type default)
		)
	)
	(wire
		(pts
			(xy 231.14 78.74) (xy 233.68 78.74)
		)
		(stroke
			(width 0)
			(type default)
		)
	)
	(wire
		(pts
			(xy 284.48 200.66) (xy 262.89 200.66)
		)
		(stroke
			(width 0)
			(type default)
		)
	)
	(wire
		(pts
			(xy 187.96 186.69) (xy 198.12 186.69)
		)
		(stroke
			(width 0)
			(type default)
		)
	)
	(wire
		(pts
			(xy 165.1 201.93) (xy 165.1 210.82)
		)
		(stroke
			(width 0)
			(type default)
		)
	)
	(wire
		(pts
			(xy 209.55 76.2) (xy 209.55 60.96)
		)
		(stroke
			(width 0)
			(type default)
		)
	)
	(wire
		(pts
			(xy 165.1 176.53) (xy 153.67 176.53)
		)
		(stroke
			(width 0)
			(type default)
		)
	)
	(wire
		(pts
			(xy 187.96 176.53) (xy 187.96 179.07)
		)
		(stroke
			(width 0)
			(type default)
		)
	)
	(wire
		(pts
			(xy 234.95 176.53) (xy 234.95 190.5)
		)
		(stroke
			(width 0)
			(type default)
		)
	)
	(wire
		(pts
			(xy 200.66 87.63) (xy 200.66 90.17)
		)
		(stroke
			(width 0)
			(type default)
		)
	)
	(wire
		(pts
			(xy 242.57 73.66) (xy 242.57 74.93)
		)
		(stroke
			(width 0)
			(type default)
		)
	)
	(wire
		(pts
			(xy 233.68 200.66) (xy 257.81 200.66)
		)
		(stroke
			(width 0)
			(type default)
		)
	)
	(wire
		(pts
			(xy 200.66 60.96) (xy 200.66 63.5)
		)
		(stroke
			(width 0)
			(type default)
		)
	)
	(bus
		(pts
			(xy 198.12 228.6) (xy 275.59 228.6)
		)
		(stroke
			(width 0)
			(type default)
		)
	)
	(bus
		(pts
			(xy 186.69 195.58) (xy 187.96 195.58)
		)
		(stroke
			(width 0)
			(type default)
		)
	)
	(wire
		(pts
			(xy 209.55 60.96) (xy 200.66 60.96)
		)
		(stroke
			(width 0)
			(type default)
		)
	)
	(wire
		(pts
			(xy 176.53 176.53) (xy 176.53 179.07)
		)
		(stroke
			(width 0)
			(type default)
		)
	)
	(wire
		(pts
			(xy 231.14 76.2) (xy 233.68 76.2)
		)
		(stroke
			(width 0)
			(type default)
		)
	)
	(wire
		(pts
			(xy 265.43 186.69) (xy 265.43 187.96)
		)
		(stroke
			(width 0)
			(type default)
		)
	)
	(wire
		(pts
			(xy 242.57 80.01) (xy 242.57 81.28)
		)
		(stroke
			(width 0)
			(type default)
		)
	)
	(wire
		(pts
			(xy 187.96 176.53) (xy 198.12 176.53)
		)
		(stroke
			(width 0)
			(type default)
		)
	)
	(wire
		(pts
			(xy 242.57 73.66) (xy 252.73 73.66)
		)
		(stroke
			(width 0)
			(type default)
		)
	)
	(bus
		(pts
			(xy 285.75 195.58) (xy 285.75 196.85)
		)
		(stroke
			(width 0)
			(type default)
		)
	)
	(bus
		(pts
			(xy 267.97 73.66) (xy 267.97 76.2)
		)
		(stroke
			(width 0)
			(type default)
		)
	)
	(bus
		(pts
			(xy 196.85 212.09) (xy 196.85 227.33)
		)
		(stroke
			(width 0)
			(type default)
		)
	)
	(bus
		(pts
			(xy 285.75 196.85) (xy 285.75 199.39)
		)
		(stroke
			(width 0)
			(type default)
		)
	)
	(polyline
		(pts
			(xy 12.7 134.62) (xy 407.67 134.62)
		)
		(stroke
			(width 0)
			(type default)
		)
	)
	(wire
		(pts
			(xy 176.53 184.15) (xy 176.53 186.69)
		)
		(stroke
			(width 0)
			(type default)
		)
	)
	(wire
		(pts
			(xy 209.55 81.28) (xy 209.55 90.17)
		)
		(stroke
			(width 0)
			(type default)
		)
	)
	(wire
		(pts
			(xy 176.53 176.53) (xy 187.96 176.53)
		)
		(stroke
			(width 0)
			(type default)
		)
	)
	(wire
		(pts
			(xy 207.01 176.53) (xy 198.12 176.53)
		)
		(stroke
			(width 0)
			(type default)
		)
	)
	(wire
		(pts
			(xy 185.42 219.71) (xy 185.42 222.25)
		)
		(stroke
			(width 0)
			(type default)
		)
	)
	(wire
		(pts
			(xy 255.27 176.53) (xy 265.43 176.53)
		)
		(stroke
			(width 0)
			(type default)
		)
	)
	(wire
		(pts
			(xy 198.12 184.15) (xy 198.12 186.69)
		)
		(stroke
			(width 0)
			(type default)
		)
	)
	(wire
		(pts
			(xy 233.68 78.74) (xy 233.68 81.28)
		)
		(stroke
			(width 0)
			(type default)
		)
	)
	(wire
		(pts
			(xy 165.1 210.82) (xy 165.1 214.63)
		)
		(stroke
			(width 0)
			(type default)
		)
	)
	(wire
		(pts
			(xy 242.57 81.28) (xy 252.73 81.28)
		)
		(stroke
			(width 0)
			(type default)
		)
	)
	(wire
		(pts
			(xy 207.01 190.5) (xy 208.28 190.5)
		)
		(stroke
			(width 0)
			(type default)
		)
	)
	(wire
		(pts
			(xy 234.95 190.5) (xy 234.95 193.04)
		)
		(stroke
			(width 0)
			(type default)
		)
	)
	(wire
		(pts
			(xy 198.12 210.82) (xy 208.28 210.82)
		)
		(stroke
			(width 0)
			(type default)
		)
	)
	(bus
		(pts
			(xy 285.75 71.12) (xy 269.24 71.12)
		)
		(stroke
			(width 0)
			(type default)
		)
	)
	(wire
		(pts
			(xy 265.43 179.07) (xy 265.43 176.53)
		)
		(stroke
			(width 0)
			(type default)
		)
	)
	(wire
		(pts
			(xy 207.01 190.5) (xy 207.01 176.53)
		)
		(stroke
			(width 0)
			(type default)
		)
	)
	(wire
		(pts
			(xy 187.96 184.15) (xy 187.96 186.69)
		)
		(stroke
			(width 0)
			(type default)
		)
	)
	(wire
		(pts
			(xy 189.23 195.58) (xy 208.28 195.58)
		)
		(stroke
			(width 0)
			(type default)
		)
	)
	(wire
		(pts
			(xy 209.55 76.2) (xy 212.09 76.2)
		)
		(stroke
			(width 0)
			(type default)
		)
	)
	(bus
		(pts
			(xy 267.97 72.39) (xy 267.97 73.66)
		)
		(stroke
			(width 0)
			(type default)
		)
	)
	(wire
		(pts
			(xy 284.48 198.12) (xy 262.89 198.12)
		)
		(stroke
			(width 0)
			(type default)
		)
	)
	(wire
		(pts
			(xy 200.66 68.58) (xy 200.66 71.12)
		)
		(stroke
			(width 0)
			(type default)
		)
	)
	(wire
		(pts
			(xy 243.84 176.53) (xy 243.84 179.07)
		)
		(stroke
			(width 0)
			(type default)
		)
	)
	(wire
		(pts
			(xy 233.68 81.28) (xy 242.57 81.28)
		)
		(stroke
			(width 0)
			(type default)
		)
	)
	(bus
		(pts
			(xy 285.75 199.39) (xy 285.75 207.01)
		)
		(stroke
			(width 0)
			(type default)
		)
	)
	(wire
		(pts
			(xy 252.73 76.2) (xy 265.43 76.2)
		)
		(stroke
			(width 0)
			(type default)
		)
	)
	(wire
		(pts
			(xy 198.12 176.53) (xy 198.12 179.07)
		)
		(stroke
			(width 0)
			(type default)
		)
	)
	(wire
		(pts
			(xy 233.68 190.5) (xy 234.95 190.5)
		)
		(stroke
			(width 0)
			(type default)
		)
	)
	(wire
		(pts
			(xy 195.58 78.74) (xy 200.66 78.74)
		)
		(stroke
			(width 0)
			(type default)
		)
	)
	(wire
		(pts
			(xy 170.18 176.53) (xy 176.53 176.53)
		)
		(stroke
			(width 0)
			(type default)
		)
	)
	(wire
		(pts
			(xy 243.84 184.15) (xy 243.84 186.69)
		)
		(stroke
			(width 0)
			(type default)
		)
	)
	(wire
		(pts
			(xy 252.73 78.74) (xy 265.43 78.74)
		)
		(stroke
			(width 0)
			(type default)
		)
	)
	(wire
		(pts
			(xy 198.12 208.28) (xy 208.28 208.28)
		)
		(stroke
			(width 0)
			(type default)
		)
	)
	(wire
		(pts
			(xy 208.28 204.47) (xy 185.42 204.47)
		)
		(stroke
			(width 0)
			(type default)
		)
	)
	(wire
		(pts
			(xy 200.66 78.74) (xy 212.09 78.74)
		)
		(stroke
			(width 0)
			(type default)
		)
	)
	(wire
		(pts
			(xy 233.68 193.04) (xy 234.95 193.04)
		)
		(stroke
			(width 0)
			(type default)
		)
	)
	(wire
		(pts
			(xy 200.66 78.74) (xy 200.66 82.55)
		)
		(stroke
			(width 0)
			(type default)
		)
	)
	(label "PLL_XI"
		(at 199.39 201.93 0)
		(effects
			(font
				(size 1.27 1.27)
			)
			(justify left bottom)
		)
	)
	(label "I2C.SDA"
		(at 199.39 208.28 0)
		(effects
			(font
				(size 1.27 1.27)
			)
			(justify left bottom)
		)
	)
	(label "PLL.CLK2"
		(at 274.32 200.66 0)
		(effects
			(font
				(size 1.27 1.27)
			)
			(justify left bottom)
		)
	)
	(label "SYS.CLK_P"
		(at 254 76.2 0)
		(effects
			(font
				(size 1.27 1.27)
			)
			(justify left bottom)
		)
	)
	(label "I2C.SCL"
		(at 199.39 210.82 0)
		(effects
			(font
				(size 1.27 1.27)
			)
			(justify left bottom)
		)
	)
	(label "SYS.CLK_N"
		(at 254 78.74 0)
		(effects
			(font
				(size 1.27 1.27)
			)
			(justify left bottom)
		)
	)
	(label "PLL.CLK0"
		(at 342.265 219.71 180)
		(effects
			(font
				(size 1.27 1.27)
			)
			(justify right bottom)
		)
	)
	(label "PLL_XO"
		(at 199.39 204.47 0)
		(effects
			(font
				(size 1.27 1.27)
			)
			(justify left bottom)
		)
	)
	(label "PLL.CLK0"
		(at 274.32 198.12 0)
		(effects
			(font
				(size 1.27 1.27)
			)
			(justify left bottom)
		)
	)
	(label "PLL_Y1"
		(at 237.49 200.66 0)
		(effects
			(font
				(size 1.27 1.27)
			)
			(justify left bottom)
		)
	)
	(label "SUP_MCU.PG_3V3"
		(at 205.74 195.58 180)
		(effects
			(font
				(size 1.27 1.27)
			)
			(justify right bottom)
		)
	)
	(label "PLL.CLK1"
		(at 274.32 208.28 0)
		(effects
			(font
				(size 1.27 1.27)
			)
			(justify left bottom)
		)
	)
	(label "PLL_Y4"
		(at 237.49 208.28 0)
		(effects
			(font
				(size 1.27 1.27)
			)
			(justify left bottom)
		)
	)
	(label "PLL_Y0"
		(at 237.49 198.12 0)
		(effects
			(font
				(size 1.27 1.27)
			)
			(justify left bottom)
		)
	)
	(hierarchical_label "PLL{PLL-CLK}"
		(shape output)
		(at 290.83 194.31 0)
		(effects
			(font
				(size 1.27 1.27)
			)
			(justify left)
		)
	)
	(hierarchical_label "LVDS_XO_200M_ENA"
		(shape input)
		(at 195.58 78.74 180)
		(effects
			(font
				(size 1.27 1.27)
			)
			(justify right)
		)
	)
	(hierarchical_label "I2C{I2C}"
		(shape bidirectional)
		(at 275.59 228.6 0)
		(effects
			(font
				(size 1.27 1.27)
			)
			(justify left)
		)
	)
	(hierarchical_label "SUP_MCU{SUP-MCU}"
		(shape bidirectional)
		(at 186.69 195.58 180)
		(effects
			(font
				(size 1.27 1.27)
			)
			(justify right)
		)
	)
	(hierarchical_label "SYS{CLK}"
		(shape output)
		(at 285.75 71.12 0)
		(effects
			(font
				(size 1.27 1.27)
			)
			(justify left)
		)
	)
	(symbol
		(lib_id "antmicroCapacitors0402:C_100n_0402")
		(at 255.27 179.07 90)
		(mirror x)
		(unit 1)
		(exclude_from_sim no)
		(in_bom yes)
		(on_board yes)
		(dnp no)
		(property "Reference" "C372"
			(at 255.905 179.705 90)
			(effects
				(font
					(size 1.27 1.27)
				)
				(justify right)
			)
		)
		(property "Value" "C_100n_0402"
			(at 265.43 199.39 0)
			(effects
				(font
					(size 1.27 1.27)
					(thickness 0.15)
				)
				(justify left bottom)
				(hide yes)
			)
		)
		(property "Footprint" "antmicro-footprints:C_0402_1005Metric"
			(at 267.97 199.39 0)
			(effects
				(font
					(size 1.27 1.27)
					(thickness 0.15)
				)
				(justify left bottom)
				(hide yes)
			)
		)
		(property "Datasheet" "https://www.murata.com/products/productdetail?partno=GRM155R61H104KE14%23"
			(at 270.51 199.39 0)
			(effects
				(font
					(size 1.27 1.27)
					(thickness 0.15)
				)
				(justify left bottom)
				(hide yes)
			)
		)
		(property "Description" ""
			(at 255.27 179.07 0)
			(effects
				(font
					(size 1.27 1.27)
				)
			)
		)
		(property "Manufacturer" "Murata"
			(at 275.59 199.39 0)
			(effects
				(font
					(size 1.27 1.27)
					(thickness 0.15)
				)
				(justify left bottom)
				(hide yes)
			)
		)
		(property "MPN" "GRM155R61H104KE14D"
			(at 273.05 199.39 0)
			(effects
				(font
					(size 1.27 1.27)
					(thickness 0.15)
				)
				(justify left bottom)
				(hide yes)
			)
		)
		(property "Val" "100n"
			(at 255.905 183.515 90)
			(effects
				(font
					(size 1.27 1.27)
					(thickness 0.15)
				)
				(justify right)
			)
		)
		(property "License" "Apache-2.0"
			(at 278.13 199.39 0)
			(effects
				(font
					(size 1.27 1.27)
					(thickness 0.15)
				)
				(justify left bottom)
				(hide yes)
			)
		)
		(property "Author" "Antmicro"
			(at 280.67 199.39 0)
			(effects
				(font
					(size 1.27 1.27)
					(thickness 0.15)
				)
				(justify left bottom)
				(hide yes)
			)
		)
		(property "Voltage" "50V"
			(at 283.21 199.39 0)
			(effects
				(font
					(size 1.27 1.27)
				)
				(justify left bottom)
				(hide yes)
			)
		)
		(property "Dielectric" "X5R"
			(at 285.75 199.39 0)
			(effects
				(font
					(size 1.27 1.27)
				)
				(justify left bottom)
				(hide yes)
			)
		)
		(pin "1"
		)
		(pin "2"
		)
		(instances
			(project "k410t-devboard"
				(path ""
					(reference "C372")
					(unit 1)
				)
			)
		)
	)
	(symbol
		(lib_id "antmicroCapacitors0402:C_22p_0402")
		(at 165.1 219.71 90)
		(unit 1)
		(exclude_from_sim no)
		(in_bom yes)
		(on_board yes)
		(dnp no)
		(property "Reference" "C365"
			(at 165.735 215.265 90)
			(effects
				(font
					(size 1.27 1.27)
				)
				(justify right)
			)
		)
		(property "Value" "C_22p_0402"
			(at 175.26 199.39 0)
			(effects
				(font
					(size 1.27 1.27)
					(thickness 0.15)
				)
				(justify left bottom)
				(hide yes)
			)
		)
		(property "Footprint" "antmicro-footprints:C_0402_1005Metric"
			(at 177.8 199.39 0)
			(effects
				(font
					(size 1.27 1.27)
					(thickness 0.15)
				)
				(justify left bottom)
				(hide yes)
			)
		)
		(property "Datasheet" "https://www.yageo.com/en/Chart/Download/pdf/CC0402JRNPO9BN220"
			(at 180.34 199.39 0)
			(effects
				(font
					(size 1.27 1.27)
					(thickness 0.15)
				)
				(justify left bottom)
				(hide yes)
			)
		)
		(property "Description" ""
			(at 165.1 219.71 0)
			(effects
				(font
					(size 1.27 1.27)
				)
			)
		)
		(property "Manufacturer" "YAGEO"
			(at 185.42 199.39 0)
			(effects
				(font
					(size 1.27 1.27)
					(thickness 0.15)
				)
				(justify left bottom)
				(hide yes)
			)
		)
		(property "MPN" "CC0402JRNPO9BN220"
			(at 182.88 199.39 0)
			(effects
				(font
					(size 1.27 1.27)
					(thickness 0.15)
				)
				(justify left bottom)
				(hide yes)
			)
		)
		(property "Val" "22p"
			(at 165.735 219.075 90)
			(effects
				(font
					(size 1.27 1.27)
					(thickness 0.15)
				)
				(justify right)
			)
		)
		(property "License" "Apache-2.0"
			(at 187.96 199.39 0)
			(effects
				(font
					(size 1.27 1.27)
					(thickness 0.15)
				)
				(justify left bottom)
				(hide yes)
			)
		)
		(property "Author" "Antmicro"
			(at 190.5 199.39 0)
			(effects
				(font
					(size 1.27 1.27)
					(thickness 0.15)
				)
				(justify left bottom)
				(hide yes)
			)
		)
		(property "Voltage" ""
			(at 193.04 199.39 0)
			(effects
				(font
					(size 1.27 1.27)
				)
				(justify left bottom)
				(hide yes)
			)
		)
		(property "Dielectric" ""
			(at 195.58 199.39 0)
			(effects
				(font
					(size 1.27 1.27)
				)
				(justify left bottom)
				(hide yes)
			)
		)
		(pin "1"
		)
		(pin "2"
		)
		(instances
			(project "k410t-devboard"
				(path ""
					(reference "C365")
					(unit 1)
				)
			)
		)
	)
	(symbol
		(lib_id "antmicroCapacitors0402:C_10u_0402")
		(at 176.53 184.15 90)
		(unit 1)
		(exclude_from_sim no)
		(in_bom yes)
		(on_board yes)
		(dnp no)
		(fields_autoplaced yes)
		(property "Reference" "C366"
			(at 179.07 180.3335 90)
			(effects
				(font
					(size 1.27 1.27)
				)
				(justify right)
			)
		)
		(property "Value" "C_10u_0402"
			(at 186.69 163.83 0)
			(effects
				(font
					(size 1.27 1.27)
					(thickness 0.15)
				)
				(justify left bottom)
				(hide yes)
			)
		)
		(property "Footprint" "antmicro-footprints:C_0402_1005Metric"
			(at 189.23 163.83 0)
			(effects
				(font
					(size 1.27 1.27)
					(thickness 0.15)
				)
				(justify left bottom)
				(hide yes)
			)
		)
		(property "Datasheet" "https://www.yageo.com/en/Chart/Download/pdf/CC0402MRX5R5BB106"
			(at 191.77 163.83 0)
			(effects
				(font
					(size 1.27 1.27)
					(thickness 0.15)
				)
				(justify left bottom)
				(hide yes)
			)
		)
		(property "Description" ""
			(at 176.53 184.15 0)
			(effects
				(font
					(size 1.27 1.27)
				)
			)
		)
		(property "Manufacturer" "YAGEO"
			(at 196.85 163.83 0)
			(effects
				(font
					(size 1.27 1.27)
					(thickness 0.15)
				)
				(justify left bottom)
				(hide yes)
			)
		)
		(property "MPN" "CC0402MRX5R5BB106"
			(at 194.31 163.83 0)
			(effects
				(font
					(size 1.27 1.27)
					(thickness 0.15)
				)
				(justify left bottom)
				(hide yes)
			)
		)
		(property "Val" "10u"
			(at 179.07 182.8735 90)
			(effects
				(font
					(size 1.27 1.27)
					(thickness 0.15)
				)
				(justify right)
			)
		)
		(property "License" "Apache-2.0"
			(at 199.39 163.83 0)
			(effects
				(font
					(size 1.27 1.27)
					(thickness 0.15)
				)
				(justify left bottom)
				(hide yes)
			)
		)
		(property "Author" "Antmicro"
			(at 201.93 163.83 0)
			(effects
				(font
					(size 1.27 1.27)
					(thickness 0.15)
				)
				(justify left bottom)
				(hide yes)
			)
		)
		(property "Voltage" ""
			(at 204.47 163.83 0)
			(effects
				(font
					(size 1.27 1.27)
				)
				(justify left bottom)
				(hide yes)
			)
		)
		(property "Dielectric" ""
			(at 207.01 163.83 0)
			(effects
				(font
					(size 1.27 1.27)
				)
				(justify left bottom)
				(hide yes)
			)
		)
		(pin "1"
		)
		(pin "2"
		)
		(instances
			(project "k410t-devboard"
				(path ""
					(reference "C366")
					(unit 1)
				)
			)
		)
	)
	(symbol
		(lib_id "antmicropower:GND")
		(at 176.53 187.96 0)
		(unit 1)
		(exclude_from_sim no)
		(in_bom yes)
		(on_board yes)
		(dnp no)
		(property "Reference" "#PWR0462"
			(at 176.53 194.31 0)
			(effects
				(font
					(size 1.27 1.27)
				)
				(hide yes)
			)
		)
		(property "Value" "GND"
			(at 176.53 191.77 0)
			(effects
				(font
					(size 1.27 1.27)
				)
			)
		)
		(property "Footprint" ""
			(at 185.42 195.58 0)
			(effects
				(font
					(size 1.27 1.27)
					(thickness 0.15)
				)
				(justify left bottom)
				(hide yes)
			)
		)
		(property "Datasheet" ""
			(at 185.42 200.66 0)
			(effects
				(font
					(size 1.27 1.27)
					(thickness 0.15)
				)
				(justify left bottom)
				(hide yes)
			)
		)
		(property "Description" ""
			(at 176.53 187.96 0)
			(effects
				(font
					(size 1.27 1.27)
				)
			)
		)
		(property "Author" "Antmicro"
			(at 185.42 195.58 0)
			(effects
				(font
					(size 1.27 1.27)
					(thickness 0.15)
				)
				(justify left bottom)
				(hide yes)
			)
		)
		(property "License" "Apache-2.0"
			(at 185.42 198.12 0)
			(effects
				(font
					(size 1.27 1.27)
					(thickness 0.15)
				)
				(justify left bottom)
				(hide yes)
			)
		)
		(pin "1"
		)
		(instances
			(project "k410t-devboard"
				(path ""
					(reference "#PWR0462")
					(unit 1)
				)
			)
		)
	)
	(symbol
		(lib_id "antmicropower:GND")
		(at 265.43 187.96 0)
		(mirror y)
		(unit 1)
		(exclude_from_sim no)
		(in_bom yes)
		(on_board yes)
		(dnp no)
		(property "Reference" "#PWR0471"
			(at 265.43 194.31 0)
			(effects
				(font
					(size 1.27 1.27)
				)
				(hide yes)
			)
		)
		(property "Value" "GND"
			(at 265.43 191.77 0)
			(effects
				(font
					(size 1.27 1.27)
				)
			)
		)
		(property "Footprint" ""
			(at 256.54 195.58 0)
			(effects
				(font
					(size 1.27 1.27)
					(thickness 0.15)
				)
				(justify left bottom)
				(hide yes)
			)
		)
		(property "Datasheet" ""
			(at 256.54 200.66 0)
			(effects
				(font
					(size 1.27 1.27)
					(thickness 0.15)
				)
				(justify left bottom)
				(hide yes)
			)
		)
		(property "Description" ""
			(at 265.43 187.96 0)
			(effects
				(font
					(size 1.27 1.27)
				)
			)
		)
		(property "Author" "Antmicro"
			(at 256.54 195.58 0)
			(effects
				(font
					(size 1.27 1.27)
					(thickness 0.15)
				)
				(justify left bottom)
				(hide yes)
			)
		)
		(property "License" "Apache-2.0"
			(at 256.54 198.12 0)
			(effects
				(font
					(size 1.27 1.27)
					(thickness 0.15)
				)
				(justify left bottom)
				(hide yes)
			)
		)
		(pin "1"
		)
		(instances
			(project "k410t-devboard"
				(path ""
					(reference "#PWR0471")
					(unit 1)
				)
			)
		)
	)
	(symbol
		(lib_id "antmicropower:GND")
		(at 200.66 90.17 0)
		(unit 1)
		(exclude_from_sim no)
		(in_bom yes)
		(on_board yes)
		(dnp no)
		(fields_autoplaced yes)
		(property "Reference" "#PWR0467"
			(at 200.66 96.52 0)
			(effects
				(font
					(size 1.27 1.27)
				)
				(hide yes)
			)
		)
		(property "Value" "GND"
			(at 200.66 93.98 0)
			(effects
				(font
					(size 1.27 1.27)
				)
			)
		)
		(property "Footprint" ""
			(at 209.55 97.79 0)
			(effects
				(font
					(size 1.27 1.27)
					(thickness 0.15)
				)
				(justify left bottom)
				(hide yes)
			)
		)
		(property "Datasheet" ""
			(at 209.55 102.87 0)
			(effects
				(font
					(size 1.27 1.27)
					(thickness 0.15)
				)
				(justify left bottom)
				(hide yes)
			)
		)
		(property "Description" ""
			(at 200.66 90.17 0)
			(effects
				(font
					(size 1.27 1.27)
				)
			)
		)
		(property "Author" "Antmicro"
			(at 209.55 97.79 0)
			(effects
				(font
					(size 1.27 1.27)
					(thickness 0.15)
				)
				(justify left bottom)
				(hide yes)
			)
		)
		(property "License" "Apache-2.0"
			(at 209.55 100.33 0)
			(effects
				(font
					(size 1.27 1.27)
					(thickness 0.15)
				)
				(justify left bottom)
				(hide yes)
			)
		)
		(pin "1"
		)
		(instances
			(project "k410t-devboard"
				(path ""
					(reference "#PWR0467")
					(unit 1)
				)
			)
		)
	)
	(symbol
		(lib_id "antmicropower:+3.3V")
		(at 153.67 170.18 0)
		(unit 1)
		(exclude_from_sim no)
		(in_bom yes)
		(on_board yes)
		(dnp no)
		(fields_autoplaced yes)
		(property "Reference" "#PWR0411"
			(at 153.67 173.99 0)
			(effects
				(font
					(size 1.27 1.27)
				)
				(hide yes)
			)
		)
		(property "Value" "+3V3"
			(at 153.67 166.624 0)
			(effects
				(font
					(size 1.27 1.27)
				)
			)
		)
		(property "Footprint" ""
			(at 153.67 170.18 0)
			(effects
				(font
					(size 1.27 1.27)
				)
				(hide yes)
			)
		)
		(property "Datasheet" ""
			(at 153.67 170.18 0)
			(effects
				(font
					(size 1.27 1.27)
				)
				(hide yes)
			)
		)
		(property "Description" ""
			(at 153.67 170.18 0)
			(effects
				(font
					(size 1.27 1.27)
				)
			)
		)
		(pin "1"
		)
		(instances
			(project "k410t-devboard"
				(path ""
					(reference "#PWR0411")
					(unit 1)
				)
			)
		)
	)
	(symbol
		(lib_id "antmicroOscillators:Oscillator_200MHz_AX3DC")
		(at 212.09 76.2 0)
		(unit 1)
		(exclude_from_sim no)
		(in_bom yes)
		(on_board yes)
		(dnp no)
		(fields_autoplaced yes)
		(property "Reference" "Y6"
			(at 221.615 68.58 0)
			(effects
				(font
					(size 1.27 1.27)
				)
			)
		)
		(property "Value" "Oscillator_200MHz_AX3DC"
			(at 221.615 72.39 0)
			(effects
				(font
					(size 1.27 1.27)
					(thickness 0.15)
				)
				(hide yes)
			)
		)
		(property "Footprint" "antmicro-footprints:Oscillator_SMD_Abracon_AX3_3.2x2.5x1mm"
			(at 245.11 86.36 0)
			(effects
				(font
					(size 1.27 1.27)
					(thickness 0.15)
				)
				(justify left bottom)
				(hide yes)
			)
		)
		(property "Datasheet" "https://abracon.com/datasheets/AX3.pdf"
			(at 245.11 88.9 0)
			(effects
				(font
					(size 1.27 1.27)
					(thickness 0.15)
				)
				(justify left bottom)
				(hide yes)
			)
		)
		(property "Description" ""
			(at 212.09 76.2 0)
			(effects
				(font
					(size 1.27 1.27)
				)
			)
		)
		(property "MPN" "AX3DCF1-200.0000"
			(at 245.11 91.44 0)
			(effects
				(font
					(size 1.27 1.27)
					(thickness 0.15)
				)
				(justify left bottom)
				(hide yes)
			)
		)
		(property "Manufacturer" "Abracon"
			(at 245.11 93.98 0)
			(effects
				(font
					(size 1.27 1.27)
					(thickness 0.15)
				)
				(justify left bottom)
				(hide yes)
			)
		)
		(property "Author" "Antmicro"
			(at 245.11 96.52 0)
			(effects
				(font
					(size 1.27 1.27)
					(thickness 0.15)
				)
				(justify left bottom)
				(hide yes)
			)
		)
		(property "License" "Apache-2.0"
			(at 245.11 99.06 0)
			(effects
				(font
					(size 1.27 1.27)
					(thickness 0.15)
				)
				(justify left bottom)
				(hide yes)
			)
		)
		(property "Val" "200 MHz"
			(at 221.615 71.12 0)
			(effects
				(font
					(size 1.27 1.27)
					(thickness 0.15)
				)
			)
		)
		(pin "1"
		)
		(pin "3"
		)
		(pin "4"
		)
		(pin "5"
		)
		(pin "6"
		)
		(pin "2"
		)
		(instances
			(project "k410t-devboard"
				(path ""
					(reference "Y6")
					(unit 1)
				)
			)
		)
	)
	(symbol
		(lib_id "antmicroResistors0402:R_22R_0402")
		(at 257.81 200.66 0)
		(unit 1)
		(exclude_from_sim no)
		(in_bom yes)
		(on_board yes)
		(dnp no)
		(property "Reference" "R336"
			(at 265.43 199.39 0)
			(effects
				(font
					(size 1.27 1.27)
				)
			)
		)
		(property "Value" "R_22R_0402"
			(at 278.13 213.36 0)
			(effects
				(font
					(size 1.27 1.27)
					(thickness 0.15)
				)
				(justify left bottom)
				(hide yes)
			)
		)
		(property "Footprint" "antmicro-footprints:R_0402_1005Metric"
			(at 278.13 215.9 0)
			(effects
				(font
					(size 1.27 1.27)
					(thickness 0.15)
				)
				(justify left bottom)
				(hide yes)
			)
		)
		(property "Datasheet" "https://www.bourns.com/docs/product-datasheets/cr.pdf"
			(at 278.13 218.44 0)
			(effects
				(font
					(size 1.27 1.27)
					(thickness 0.15)
				)
				(justify left bottom)
				(hide yes)
			)
		)
		(property "Description" ""
			(at 257.81 200.66 0)
			(effects
				(font
					(size 1.27 1.27)
				)
			)
		)
		(property "Manufacturer" "Bourns"
			(at 278.13 223.52 0)
			(effects
				(font
					(size 1.27 1.27)
					(thickness 0.15)
				)
				(justify left bottom)
				(hide yes)
			)
		)
		(property "MPN" "CR0402-FX-22R0GLF"
			(at 278.13 220.98 0)
			(effects
				(font
					(size 1.27 1.27)
					(thickness 0.15)
				)
				(justify left bottom)
				(hide yes)
			)
		)
		(property "Val" "22R"
			(at 255.905 199.39 0)
			(effects
				(font
					(size 1.27 1.27)
					(thickness 0.15)
				)
			)
		)
		(property "License" "Apache-2.0"
			(at 278.13 226.06 0)
			(effects
				(font
					(size 1.27 1.27)
					(thickness 0.15)
				)
				(justify left bottom)
				(hide yes)
			)
		)
		(property "Author" "Antmicro"
			(at 278.13 228.6 0)
			(effects
				(font
					(size 1.27 1.27)
					(thickness 0.15)
				)
				(justify left bottom)
				(hide yes)
			)
		)
		(property "Tolerance" "1%"
			(at 278.13 210.82 0)
			(effects
				(font
					(size 1.27 1.27)
				)
				(justify left bottom)
				(hide yes)
			)
		)
		(pin "1"
		)
		(pin "2"
		)
		(instances
			(project "k410t-devboard"
				(path ""
					(reference "R336")
					(unit 1)
				)
			)
		)
	)
	(symbol
		(lib_id "antmicropower:GND")
		(at 220.98 222.25 0)
		(unit 1)
		(exclude_from_sim no)
		(in_bom yes)
		(on_board yes)
		(dnp no)
		(property "Reference" "#PWR0470"
			(at 220.98 228.6 0)
			(effects
				(font
					(size 1.27 1.27)
				)
				(hide yes)
			)
		)
		(property "Value" "GND"
			(at 220.98 226.06 0)
			(effects
				(font
					(size 1.27 1.27)
				)
			)
		)
		(property "Footprint" ""
			(at 229.87 229.87 0)
			(effects
				(font
					(size 1.27 1.27)
					(thickness 0.15)
				)
				(justify left bottom)
				(hide yes)
			)
		)
		(property "Datasheet" ""
			(at 229.87 234.95 0)
			(effects
				(font
					(size 1.27 1.27)
					(thickness 0.15)
				)
				(justify left bottom)
				(hide yes)
			)
		)
		(property "Description" ""
			(at 220.98 222.25 0)
			(effects
				(font
					(size 1.27 1.27)
				)
			)
		)
		(property "Author" "Antmicro"
			(at 229.87 229.87 0)
			(effects
				(font
					(size 1.27 1.27)
					(thickness 0.15)
				)
				(justify left bottom)
				(hide yes)
			)
		)
		(property "License" "Apache-2.0"
			(at 229.87 232.41 0)
			(effects
				(font
					(size 1.27 1.27)
					(thickness 0.15)
				)
				(justify left bottom)
				(hide yes)
			)
		)
		(pin "1"
		)
		(instances
			(project "k410t-devboard"
				(path ""
					(reference "#PWR0470")
					(unit 1)
				)
			)
		)
	)
	(symbol
		(lib_id "antmicroResistors0402:R_100R_0402")
		(at 242.57 80.01 90)
		(unit 1)
		(exclude_from_sim no)
		(in_bom yes)
		(on_board yes)
		(dnp no)
		(fields_autoplaced yes)
		(property "Reference" "R334"
			(at 245.11 76.1999 90)
			(effects
				(font
					(size 1.27 1.27)
				)
				(justify right)
			)
		)
		(property "Value" "R_100R_0402"
			(at 255.27 59.69 0)
			(effects
				(font
					(size 1.27 1.27)
					(thickness 0.15)
				)
				(justify left bottom)
				(hide yes)
			)
		)
		(property "Footprint" "antmicro-footprints:R_0402_1005Metric"
			(at 257.81 59.69 0)
			(effects
				(font
					(size 1.27 1.27)
					(thickness 0.15)
				)
				(justify left bottom)
				(hide yes)
			)
		)
		(property "Datasheet" "https://www.bourns.com/docs/product-datasheets/cr.pdf"
			(at 260.35 59.69 0)
			(effects
				(font
					(size 1.27 1.27)
					(thickness 0.15)
				)
				(justify left bottom)
				(hide yes)
			)
		)
		(property "Description" ""
			(at 242.57 80.01 0)
			(effects
				(font
					(size 1.27 1.27)
				)
			)
		)
		(property "Manufacturer" "Bourns"
			(at 265.43 59.69 0)
			(effects
				(font
					(size 1.27 1.27)
					(thickness 0.15)
				)
				(justify left bottom)
				(hide yes)
			)
		)
		(property "MPN" "CR0402-FX-1000GLF"
			(at 262.89 59.69 0)
			(effects
				(font
					(size 1.27 1.27)
					(thickness 0.15)
				)
				(justify left bottom)
				(hide yes)
			)
		)
		(property "Val" "100R"
			(at 245.11 78.7399 90)
			(effects
				(font
					(size 1.27 1.27)
					(thickness 0.15)
				)
				(justify right)
			)
		)
		(property "License" "Apache-2.0"
			(at 267.97 59.69 0)
			(effects
				(font
					(size 1.27 1.27)
					(thickness 0.15)
				)
				(justify left bottom)
				(hide yes)
			)
		)
		(property "Author" "Antmicro"
			(at 270.51 59.69 0)
			(effects
				(font
					(size 1.27 1.27)
					(thickness 0.15)
				)
				(justify left bottom)
				(hide yes)
			)
		)
		(property "Tolerance" "1%"
			(at 252.73 59.69 0)
			(effects
				(font
					(size 1.27 1.27)
				)
				(justify left bottom)
				(hide yes)
			)
		)
		(pin "1"
		)
		(pin "2"
		)
		(instances
			(project "k410t-devboard"
				(path ""
					(reference "R334")
					(unit 1)
				)
			)
		)
	)
	(symbol
		(lib_id "antmicroCoaxialConnectorsRF:U_FL-R-SMT-1")
		(at 328.93 219.71 0)
		(mirror y)
		(unit 1)
		(exclude_from_sim no)
		(in_bom yes)
		(on_board yes)
		(dnp no)
		(fields_autoplaced yes)
		(property "Reference" "J3"
			(at 322.9438 213.36 0)
			(effects
				(font
					(size 1.27 1.27)
				)
			)
		)
		(property "Value" "U_FL-R-SMT-1"
			(at 308.61 227.33 0)
			(effects
				(font
					(size 1.27 1.27)
					(thickness 0.15)
				)
				(justify left bottom)
				(hide yes)
			)
		)
		(property "Footprint" "antmicro-footprints:Coax_Conn_U.FL"
			(at 308.61 229.87 0)
			(effects
				(font
					(size 1.27 1.27)
					(thickness 0.15)
				)
				(justify left bottom)
				(hide yes)
			)
		)
		(property "Datasheet" "https://media.digikey.com/pdf/Data%20Sheets/Hirose%20PDFs/UFL%20Series.pdf"
			(at 308.61 232.41 0)
			(effects
				(font
					(size 1.27 1.27)
					(thickness 0.15)
				)
				(justify left bottom)
				(hide yes)
			)
		)
		(property "Description" ""
			(at 328.93 219.71 0)
			(effects
				(font
					(size 1.27 1.27)
				)
			)
		)
		(property "MPN" "U.FL-R-SMT-1(10)"
			(at 322.9438 215.9 0)
			(effects
				(font
					(size 1.27 1.27)
					(thickness 0.15)
				)
			)
		)
		(property "Manufacturer" "Hirose Electric"
			(at 308.61 234.95 0)
			(effects
				(font
					(size 1.27 1.27)
					(thickness 0.15)
				)
				(justify left bottom)
				(hide yes)
			)
		)
		(property "Author" "Antmicro"
			(at 308.61 237.49 0)
			(effects
				(font
					(size 1.27 1.27)
					(thickness 0.15)
				)
				(justify left bottom)
				(hide yes)
			)
		)
		(property "License" "Apache-2.0"
			(at 308.61 240.03 0)
			(effects
				(font
					(size 1.27 1.27)
					(thickness 0.15)
				)
				(justify left bottom)
				(hide yes)
			)
		)
		(pin "1"
		)
		(pin "SH1"
		)
		(pin "SH2"
		)
		(instances
			(project "k410t-devboard"
				(path ""
					(reference "J3")
					(unit 1)
				)
			)
		)
	)
	(symbol
		(lib_id "antmicroResonators:Resonator_12MHz_ABM8G")
		(at 171.45 210.82 0)
		(unit 1)
		(exclude_from_sim no)
		(in_bom yes)
		(on_board yes)
		(dnp no)
		(fields_autoplaced yes)
		(property "Reference" "Y5"
			(at 175.26 203.835 0)
			(effects
				(font
					(size 1.27 1.27)
				)
			)
		)
		(property "Value" "Resonator_12MHz_ABM8G"
			(at 186.69 223.52 0)
			(effects
				(font
					(size 1.27 1.27)
					(thickness 0.15)
				)
				(justify left bottom)
				(hide yes)
			)
		)
		(property "Footprint" "antmicro-footprints:Resonator_SMD_Abracon_ABM8G_3.2x2.5mm"
			(at 186.69 226.06 0)
			(effects
				(font
					(size 1.27 1.27)
					(thickness 0.15)
				)
				(justify left bottom)
				(hide yes)
			)
		)
		(property "Datasheet" "https://abracon.com/Resonators/ABM8G.pdf"
			(at 186.69 228.6 0)
			(effects
				(font
					(size 1.27 1.27)
					(thickness 0.15)
				)
				(justify left bottom)
				(hide yes)
			)
		)
		(property "Description" ""
			(at 171.45 210.82 0)
			(effects
				(font
					(size 1.27 1.27)
				)
			)
		)
		(property "MPN" "ABM8G-12.000MHZ-18-D2Y-T"
			(at 186.69 218.44 0)
			(effects
				(font
					(size 1.27 1.27)
					(thickness 0.15)
				)
				(justify left bottom)
				(hide yes)
			)
		)
		(property "Manufacturer" "Abracon"
			(at 186.69 231.14 0)
			(effects
				(font
					(size 1.27 1.27)
					(thickness 0.15)
				)
				(justify left bottom)
				(hide yes)
			)
		)
		(property "Val" "12 MHz"
			(at 175.26 206.375 0)
			(effects
				(font
					(size 1.27 1.27)
					(thickness 0.15)
				)
			)
		)
		(property "Author" "Antmicro"
			(at 186.69 233.68 0)
			(effects
				(font
					(size 1.27 1.27)
					(thickness 0.15)
				)
				(justify left bottom)
				(hide yes)
			)
		)
		(property "License" "Apache-2.0"
			(at 186.69 236.22 0)
			(effects
				(font
					(size 1.27 1.27)
					(thickness 0.15)
				)
				(justify left bottom)
				(hide yes)
			)
		)
		(pin "1"
		)
		(pin "2"
		)
		(pin "3"
		)
		(pin "4"
		)
		(instances
			(project "k410t-devboard"
				(path ""
					(reference "Y5")
					(unit 1)
				)
			)
		)
	)
	(symbol
		(lib_id "antmicropower:GND")
		(at 175.26 222.25 0)
		(unit 1)
		(exclude_from_sim no)
		(in_bom yes)
		(on_board yes)
		(dnp no)
		(property "Reference" "#PWR0461"
			(at 175.26 228.6 0)
			(effects
				(font
					(size 1.27 1.27)
				)
				(hide yes)
			)
		)
		(property "Value" "GND"
			(at 175.26 226.06 0)
			(effects
				(font
					(size 1.27 1.27)
				)
			)
		)
		(property "Footprint" ""
			(at 184.15 229.87 0)
			(effects
				(font
					(size 1.27 1.27)
					(thickness 0.15)
				)
				(justify left bottom)
				(hide yes)
			)
		)
		(property "Datasheet" ""
			(at 184.15 234.95 0)
			(effects
				(font
					(size 1.27 1.27)
					(thickness 0.15)
				)
				(justify left bottom)
				(hide yes)
			)
		)
		(property "Description" ""
			(at 175.26 222.25 0)
			(effects
				(font
					(size 1.27 1.27)
				)
			)
		)
		(property "Author" "Antmicro"
			(at 184.15 229.87 0)
			(effects
				(font
					(size 1.27 1.27)
					(thickness 0.15)
				)
				(justify left bottom)
				(hide yes)
			)
		)
		(property "License" "Apache-2.0"
			(at 184.15 232.41 0)
			(effects
				(font
					(size 1.27 1.27)
					(thickness 0.15)
				)
				(justify left bottom)
				(hide yes)
			)
		)
		(pin "1"
		)
		(instances
			(project "k410t-devboard"
				(path ""
					(reference "#PWR0461")
					(unit 1)
				)
			)
		)
	)
	(symbol
		(lib_id "antmicropower:+3.3V")
		(at 265.43 175.26 0)
		(mirror y)
		(unit 1)
		(exclude_from_sim no)
		(in_bom yes)
		(on_board yes)
		(dnp no)
		(fields_autoplaced yes)
		(property "Reference" "#PWR0418"
			(at 265.43 179.07 0)
			(effects
				(font
					(size 1.27 1.27)
				)
				(hide yes)
			)
		)
		(property "Value" "+3V3"
			(at 265.43 171.704 0)
			(effects
				(font
					(size 1.27 1.27)
				)
			)
		)
		(property "Footprint" ""
			(at 265.43 175.26 0)
			(effects
				(font
					(size 1.27 1.27)
				)
				(hide yes)
			)
		)
		(property "Datasheet" ""
			(at 265.43 175.26 0)
			(effects
				(font
					(size 1.27 1.27)
				)
				(hide yes)
			)
		)
		(property "Description" ""
			(at 265.43 175.26 0)
			(effects
				(font
					(size 1.27 1.27)
				)
			)
		)
		(pin "1"
		)
		(instances
			(project "k410t-devboard"
				(path ""
					(reference "#PWR0418")
					(unit 1)
				)
			)
		)
	)
	(symbol
		(lib_id "antmicroResistors0402:R_10k_0402")
		(at 200.66 87.63 90)
		(unit 1)
		(exclude_from_sim no)
		(in_bom yes)
		(on_board yes)
		(dnp no)
		(property "Reference" "R352"
			(at 201.93 83.82 90)
			(effects
				(font
					(size 1.27 1.27)
				)
				(justify right)
			)
		)
		(property "Value" "R_10k_0402"
			(at 213.36 67.31 0)
			(effects
				(font
					(size 1.27 1.27)
					(thickness 0.15)
				)
				(justify left bottom)
				(hide yes)
			)
		)
		(property "Footprint" "antmicro-footprints:R_0402_1005Metric"
			(at 215.9 67.31 0)
			(effects
				(font
					(size 1.27 1.27)
					(thickness 0.15)
				)
				(justify left bottom)
				(hide yes)
			)
		)
		(property "Datasheet" "https://www.bourns.com/docs/product-datasheets/cr.pdf"
			(at 218.44 67.31 0)
			(effects
				(font
					(size 1.27 1.27)
					(thickness 0.15)
				)
				(justify left bottom)
				(hide yes)
			)
		)
		(property "Description" ""
			(at 200.66 87.63 0)
			(effects
				(font
					(size 1.27 1.27)
				)
			)
		)
		(property "Manufacturer" "Bourns"
			(at 223.52 67.31 0)
			(effects
				(font
					(size 1.27 1.27)
					(thickness 0.15)
				)
				(justify left bottom)
				(hide yes)
			)
		)
		(property "MPN" "CR0402-FX-1002GLF"
			(at 220.98 67.31 0)
			(effects
				(font
					(size 1.27 1.27)
					(thickness 0.15)
				)
				(justify left bottom)
				(hide yes)
			)
		)
		(property "Val" "10k"
			(at 201.93 86.36 90)
			(effects
				(font
					(size 1.27 1.27)
					(thickness 0.15)
				)
				(justify right)
			)
		)
		(property "License" "Apache-2.0"
			(at 226.06 67.31 0)
			(effects
				(font
					(size 1.27 1.27)
					(thickness 0.15)
				)
				(justify left bottom)
				(hide yes)
			)
		)
		(property "Author" "Antmicro"
			(at 228.6 67.31 0)
			(effects
				(font
					(size 1.27 1.27)
					(thickness 0.15)
				)
				(justify left bottom)
				(hide yes)
			)
		)
		(property "Tolerance" "1%"
			(at 210.82 67.31 0)
			(effects
				(font
					(size 1.27 1.27)
				)
				(justify left bottom)
				(hide yes)
			)
		)
		(pin "1"
		)
		(pin "2"
		)
		(instances
			(project "k410t-devboard"
				(path ""
					(reference "R352")
					(unit 1)
				)
			)
		)
	)
	(symbol
		(lib_id "antmicroCapacitors0402:C_100n_0402")
		(at 187.96 184.15 90)
		(unit 1)
		(exclude_from_sim no)
		(in_bom yes)
		(on_board yes)
		(dnp no)
		(fields_autoplaced yes)
		(property "Reference" "C368"
			(at 191.135 180.3335 90)
			(effects
				(font
					(size 1.27 1.27)
				)
				(justify right)
			)
		)
		(property "Value" "C_100n_0402"
			(at 198.12 163.83 0)
			(effects
				(font
					(size 1.27 1.27)
					(thickness 0.15)
				)
				(justify left bottom)
				(hide yes)
			)
		)
		(property "Footprint" "antmicro-footprints:C_0402_1005Metric"
			(at 200.66 163.83 0)
			(effects
				(font
					(size 1.27 1.27)
					(thickness 0.15)
				)
				(justify left bottom)
				(hide yes)
			)
		)
		(property "Datasheet" "https://www.murata.com/products/productdetail?partno=GRM155R61H104KE14%23"
			(at 203.2 163.83 0)
			(effects
				(font
					(size 1.27 1.27)
					(thickness 0.15)
				)
				(justify left bottom)
				(hide yes)
			)
		)
		(property "Description" ""
			(at 187.96 184.15 0)
			(effects
				(font
					(size 1.27 1.27)
				)
			)
		)
		(property "Manufacturer" "Murata"
			(at 208.28 163.83 0)
			(effects
				(font
					(size 1.27 1.27)
					(thickness 0.15)
				)
				(justify left bottom)
				(hide yes)
			)
		)
		(property "MPN" "GRM155R61H104KE14D"
			(at 205.74 163.83 0)
			(effects
				(font
					(size 1.27 1.27)
					(thickness 0.15)
				)
				(justify left bottom)
				(hide yes)
			)
		)
		(property "Val" "100n"
			(at 191.135 182.8735 90)
			(effects
				(font
					(size 1.27 1.27)
					(thickness 0.15)
				)
				(justify right)
			)
		)
		(property "License" "Apache-2.0"
			(at 210.82 163.83 0)
			(effects
				(font
					(size 1.27 1.27)
					(thickness 0.15)
				)
				(justify left bottom)
				(hide yes)
			)
		)
		(property "Author" "Antmicro"
			(at 213.36 163.83 0)
			(effects
				(font
					(size 1.27 1.27)
					(thickness 0.15)
				)
				(justify left bottom)
				(hide yes)
			)
		)
		(property "Voltage" "50V"
			(at 215.9 163.83 0)
			(effects
				(font
					(size 1.27 1.27)
				)
				(justify left bottom)
				(hide yes)
			)
		)
		(property "Dielectric" "X5R"
			(at 218.44 163.83 0)
			(effects
				(font
					(size 1.27 1.27)
				)
				(justify left bottom)
				(hide yes)
			)
		)
		(pin "1"
		)
		(pin "2"
		)
		(instances
			(project "k410t-devboard"
				(path ""
					(reference "C368")
					(unit 1)
				)
			)
		)
	)
	(symbol
		(lib_id "antmicropower:GND")
		(at 165.1 222.25 0)
		(unit 1)
		(exclude_from_sim no)
		(in_bom yes)
		(on_board yes)
		(dnp no)
		(property "Reference" "#PWR0459"
			(at 165.1 228.6 0)
			(effects
				(font
					(size 1.27 1.27)
				)
				(hide yes)
			)
		)
		(property "Value" "GND"
			(at 165.1 226.06 0)
			(effects
				(font
					(size 1.27 1.27)
				)
			)
		)
		(property "Footprint" ""
			(at 173.99 229.87 0)
			(effects
				(font
					(size 1.27 1.27)
					(thickness 0.15)
				)
				(justify left bottom)
				(hide yes)
			)
		)
		(property "Datasheet" ""
			(at 173.99 234.95 0)
			(effects
				(font
					(size 1.27 1.27)
					(thickness 0.15)
				)
				(justify left bottom)
				(hide yes)
			)
		)
		(property "Description" ""
			(at 165.1 222.25 0)
			(effects
				(font
					(size 1.27 1.27)
				)
			)
		)
		(property "Author" "Antmicro"
			(at 173.99 229.87 0)
			(effects
				(font
					(size 1.27 1.27)
					(thickness 0.15)
				)
				(justify left bottom)
				(hide yes)
			)
		)
		(property "License" "Apache-2.0"
			(at 173.99 232.41 0)
			(effects
				(font
					(size 1.27 1.27)
					(thickness 0.15)
				)
				(justify left bottom)
				(hide yes)
			)
		)
		(pin "1"
		)
		(instances
			(project "k410t-devboard"
				(path ""
					(reference "#PWR0459")
					(unit 1)
				)
			)
		)
	)
	(symbol
		(lib_id "antmicroResistors0402:R_22R_0402")
		(at 257.81 208.28 0)
		(unit 1)
		(exclude_from_sim no)
		(in_bom yes)
		(on_board yes)
		(dnp no)
		(property "Reference" "R337"
			(at 265.43 207.01 0)
			(effects
				(font
					(size 1.27 1.27)
				)
			)
		)
		(property "Value" "R_22R_0402"
			(at 278.13 220.98 0)
			(effects
				(font
					(size 1.27 1.27)
					(thickness 0.15)
				)
				(justify left bottom)
				(hide yes)
			)
		)
		(property "Footprint" "antmicro-footprints:R_0402_1005Metric"
			(at 278.13 223.52 0)
			(effects
				(font
					(size 1.27 1.27)
					(thickness 0.15)
				)
				(justify left bottom)
				(hide yes)
			)
		)
		(property "Datasheet" "https://www.bourns.com/docs/product-datasheets/cr.pdf"
			(at 278.13 226.06 0)
			(effects
				(font
					(size 1.27 1.27)
					(thickness 0.15)
				)
				(justify left bottom)
				(hide yes)
			)
		)
		(property "Description" ""
			(at 257.81 208.28 0)
			(effects
				(font
					(size 1.27 1.27)
				)
			)
		)
		(property "Manufacturer" "Bourns"
			(at 278.13 231.14 0)
			(effects
				(font
					(size 1.27 1.27)
					(thickness 0.15)
				)
				(justify left bottom)
				(hide yes)
			)
		)
		(property "MPN" "CR0402-FX-22R0GLF"
			(at 278.13 228.6 0)
			(effects
				(font
					(size 1.27 1.27)
					(thickness 0.15)
				)
				(justify left bottom)
				(hide yes)
			)
		)
		(property "Val" "22R"
			(at 255.905 207.01 0)
			(effects
				(font
					(size 1.27 1.27)
					(thickness 0.15)
				)
			)
		)
		(property "License" "Apache-2.0"
			(at 278.13 233.68 0)
			(effects
				(font
					(size 1.27 1.27)
					(thickness 0.15)
				)
				(justify left bottom)
				(hide yes)
			)
		)
		(property "Author" "Antmicro"
			(at 278.13 236.22 0)
			(effects
				(font
					(size 1.27 1.27)
					(thickness 0.15)
				)
				(justify left bottom)
				(hide yes)
			)
		)
		(property "Tolerance" "1%"
			(at 278.13 218.44 0)
			(effects
				(font
					(size 1.27 1.27)
				)
				(justify left bottom)
				(hide yes)
			)
		)
		(pin "1"
		)
		(pin "2"
		)
		(instances
			(project "k410t-devboard"
				(path ""
					(reference "R337")
					(unit 1)
				)
			)
		)
	)
	(symbol
		(lib_id "antmicropower:GND")
		(at 185.42 222.25 0)
		(unit 1)
		(exclude_from_sim no)
		(in_bom yes)
		(on_board yes)
		(dnp no)
		(property "Reference" "#PWR0466"
			(at 185.42 228.6 0)
			(effects
				(font
					(size 1.27 1.27)
				)
				(hide yes)
			)
		)
		(property "Value" "GND"
			(at 185.42 226.06 0)
			(effects
				(font
					(size 1.27 1.27)
				)
			)
		)
		(property "Footprint" ""
			(at 194.31 229.87 0)
			(effects
				(font
					(size 1.27 1.27)
					(thickness 0.15)
				)
				(justify left bottom)
				(hide yes)
			)
		)
		(property "Datasheet" ""
			(at 194.31 234.95 0)
			(effects
				(font
					(size 1.27 1.27)
					(thickness 0.15)
				)
				(justify left bottom)
				(hide yes)
			)
		)
		(property "Description" ""
			(at 185.42 222.25 0)
			(effects
				(font
					(size 1.27 1.27)
				)
			)
		)
		(property "Author" "Antmicro"
			(at 194.31 229.87 0)
			(effects
				(font
					(size 1.27 1.27)
					(thickness 0.15)
				)
				(justify left bottom)
				(hide yes)
			)
		)
		(property "License" "Apache-2.0"
			(at 194.31 232.41 0)
			(effects
				(font
					(size 1.27 1.27)
					(thickness 0.15)
				)
				(justify left bottom)
				(hide yes)
			)
		)
		(pin "1"
		)
		(instances
			(project "k410t-devboard"
				(path ""
					(reference "#PWR0466")
					(unit 1)
				)
			)
		)
	)
	(symbol
		(lib_id "antmicroCapacitors0402:C_22p_0402")
		(at 185.42 219.71 90)
		(unit 1)
		(exclude_from_sim no)
		(in_bom yes)
		(on_board yes)
		(dnp no)
		(property "Reference" "C367"
			(at 186.055 215.265 90)
			(effects
				(font
					(size 1.27 1.27)
				)
				(justify right)
			)
		)
		(property "Value" "C_22p_0402"
			(at 195.58 199.39 0)
			(effects
				(font
					(size 1.27 1.27)
					(thickness 0.15)
				)
				(justify left bottom)
				(hide yes)
			)
		)
		(property "Footprint" "antmicro-footprints:C_0402_1005Metric"
			(at 198.12 199.39 0)
			(effects
				(font
					(size 1.27 1.27)
					(thickness 0.15)
				)
				(justify left bottom)
				(hide yes)
			)
		)
		(property "Datasheet" "https://www.yageo.com/en/Chart/Download/pdf/CC0402JRNPO9BN220"
			(at 200.66 199.39 0)
			(effects
				(font
					(size 1.27 1.27)
					(thickness 0.15)
				)
				(justify left bottom)
				(hide yes)
			)
		)
		(property "Description" ""
			(at 185.42 219.71 0)
			(effects
				(font
					(size 1.27 1.27)
				)
			)
		)
		(property "Manufacturer" "YAGEO"
			(at 205.74 199.39 0)
			(effects
				(font
					(size 1.27 1.27)
					(thickness 0.15)
				)
				(justify left bottom)
				(hide yes)
			)
		)
		(property "MPN" "CC0402JRNPO9BN220"
			(at 203.2 199.39 0)
			(effects
				(font
					(size 1.27 1.27)
					(thickness 0.15)
				)
				(justify left bottom)
				(hide yes)
			)
		)
		(property "Val" "22p"
			(at 186.055 219.075 90)
			(effects
				(font
					(size 1.27 1.27)
					(thickness 0.15)
				)
				(justify right)
			)
		)
		(property "License" "Apache-2.0"
			(at 208.28 199.39 0)
			(effects
				(font
					(size 1.27 1.27)
					(thickness 0.15)
				)
				(justify left bottom)
				(hide yes)
			)
		)
		(property "Author" "Antmicro"
			(at 210.82 199.39 0)
			(effects
				(font
					(size 1.27 1.27)
					(thickness 0.15)
				)
				(justify left bottom)
				(hide yes)
			)
		)
		(property "Voltage" ""
			(at 213.36 199.39 0)
			(effects
				(font
					(size 1.27 1.27)
				)
				(justify left bottom)
				(hide yes)
			)
		)
		(property "Dielectric" ""
			(at 215.9 199.39 0)
			(effects
				(font
					(size 1.27 1.27)
				)
				(justify left bottom)
				(hide yes)
			)
		)
		(pin "1"
		)
		(pin "2"
		)
		(instances
			(project "k410t-devboard"
				(path ""
					(reference "C367")
					(unit 1)
				)
			)
		)
	)
	(symbol
		(lib_id "antmicroCapacitors0402:C_10u_0402")
		(at 265.43 184.15 90)
		(unit 1)
		(exclude_from_sim no)
		(in_bom yes)
		(on_board yes)
		(dnp no)
		(property "Reference" "C373"
			(at 266.065 179.705 90)
			(effects
				(font
					(size 1.27 1.27)
				)
				(justify right)
			)
		)
		(property "Value" "C_10u_0402"
			(at 275.59 163.83 0)
			(effects
				(font
					(size 1.27 1.27)
					(thickness 0.15)
				)
				(justify left bottom)
				(hide yes)
			)
		)
		(property "Footprint" "antmicro-footprints:C_0402_1005Metric"
			(at 278.13 163.83 0)
			(effects
				(font
					(size 1.27 1.27)
					(thickness 0.15)
				)
				(justify left bottom)
				(hide yes)
			)
		)
		(property "Datasheet" "https://www.yageo.com/en/Chart/Download/pdf/CC0402MRX5R5BB106"
			(at 280.67 163.83 0)
			(effects
				(font
					(size 1.27 1.27)
					(thickness 0.15)
				)
				(justify left bottom)
				(hide yes)
			)
		)
		(property "Description" ""
			(at 265.43 184.15 0)
			(effects
				(font
					(size 1.27 1.27)
				)
			)
		)
		(property "Manufacturer" "YAGEO"
			(at 285.75 163.83 0)
			(effects
				(font
					(size 1.27 1.27)
					(thickness 0.15)
				)
				(justify left bottom)
				(hide yes)
			)
		)
		(property "MPN" "CC0402MRX5R5BB106"
			(at 283.21 163.83 0)
			(effects
				(font
					(size 1.27 1.27)
					(thickness 0.15)
				)
				(justify left bottom)
				(hide yes)
			)
		)
		(property "Val" "10u"
			(at 266.065 183.515 90)
			(effects
				(font
					(size 1.27 1.27)
					(thickness 0.15)
				)
				(justify right)
			)
		)
		(property "License" "Apache-2.0"
			(at 288.29 163.83 0)
			(effects
				(font
					(size 1.27 1.27)
					(thickness 0.15)
				)
				(justify left bottom)
				(hide yes)
			)
		)
		(property "Author" "Antmicro"
			(at 290.83 163.83 0)
			(effects
				(font
					(size 1.27 1.27)
					(thickness 0.15)
				)
				(justify left bottom)
				(hide yes)
			)
		)
		(property "Voltage" ""
			(at 293.37 163.83 0)
			(effects
				(font
					(size 1.27 1.27)
				)
				(justify left bottom)
				(hide yes)
			)
		)
		(property "Dielectric" ""
			(at 295.91 163.83 0)
			(effects
				(font
					(size 1.27 1.27)
				)
				(justify left bottom)
				(hide yes)
			)
		)
		(pin "1"
		)
		(pin "2"
		)
		(instances
			(project "k410t-devboard"
				(path ""
					(reference "C373")
					(unit 1)
				)
			)
		)
	)
	(symbol
		(lib_id "antmicropower:GND")
		(at 322.58 228.6 0)
		(unit 1)
		(exclude_from_sim no)
		(in_bom yes)
		(on_board yes)
		(dnp no)
		(property "Reference" "#PWR0476"
			(at 322.58 234.95 0)
			(effects
				(font
					(size 1.27 1.27)
				)
				(hide yes)
			)
		)
		(property "Value" "GND"
			(at 322.58 232.41 0)
			(effects
				(font
					(size 1.27 1.27)
				)
			)
		)
		(property "Footprint" ""
			(at 331.47 236.22 0)
			(effects
				(font
					(size 1.27 1.27)
					(thickness 0.15)
				)
				(justify left bottom)
				(hide yes)
			)
		)
		(property "Datasheet" ""
			(at 331.47 241.3 0)
			(effects
				(font
					(size 1.27 1.27)
					(thickness 0.15)
				)
				(justify left bottom)
				(hide yes)
			)
		)
		(property "Description" ""
			(at 322.58 228.6 0)
			(effects
				(font
					(size 1.27 1.27)
				)
			)
		)
		(property "Author" "Antmicro"
			(at 331.47 236.22 0)
			(effects
				(font
					(size 1.27 1.27)
					(thickness 0.15)
				)
				(justify left bottom)
				(hide yes)
			)
		)
		(property "License" "Apache-2.0"
			(at 331.47 238.76 0)
			(effects
				(font
					(size 1.27 1.27)
					(thickness 0.15)
				)
				(justify left bottom)
				(hide yes)
			)
		)
		(pin "1"
		)
		(instances
			(project "k410t-devboard"
				(path ""
					(reference "#PWR0476")
					(unit 1)
				)
			)
		)
	)
	(symbol
		(lib_id "antmicropower:+1V8")
		(at 200.66 60.96 0)
		(unit 1)
		(exclude_from_sim no)
		(in_bom yes)
		(on_board yes)
		(dnp no)
		(fields_autoplaced yes)
		(property "Reference" "#PWR0414"
			(at 200.66 64.77 0)
			(effects
				(font
					(size 1.27 1.27)
				)
				(hide yes)
			)
		)
		(property "Value" "+1V8"
			(at 200.66 57.404 0)
			(effects
				(font
					(size 1.27 1.27)
				)
			)
		)
		(property "Footprint" ""
			(at 215.9 68.58 0)
			(effects
				(font
					(size 1.27 1.27)
					(thickness 0.15)
				)
				(justify left bottom)
				(hide yes)
			)
		)
		(property "Datasheet" ""
			(at 215.9 71.12 0)
			(effects
				(font
					(size 1.27 1.27)
					(thickness 0.15)
				)
				(justify left bottom)
				(hide yes)
			)
		)
		(property "Description" ""
			(at 200.66 60.96 0)
			(effects
				(font
					(size 1.27 1.27)
				)
			)
		)
		(property "Author" "Antmicro"
			(at 215.9 68.58 0)
			(effects
				(font
					(size 1.27 1.27)
					(thickness 0.15)
				)
				(justify left bottom)
				(hide yes)
			)
		)
		(property "License" "Apache-2.0"
			(at 215.9 71.12 0)
			(effects
				(font
					(size 1.27 1.27)
					(thickness 0.15)
				)
				(justify left bottom)
				(hide yes)
			)
		)
		(pin "1"
		)
		(instances
			(project "k410t-devboard"
				(path ""
					(reference "#PWR0414")
					(unit 1)
				)
			)
		)
	)
	(symbol
		(lib_id "antmicroResistors0402:R_22R_0402")
		(at 257.81 198.12 0)
		(unit 1)
		(exclude_from_sim no)
		(in_bom yes)
		(on_board yes)
		(dnp no)
		(property "Reference" "R335"
			(at 265.43 196.85 0)
			(effects
				(font
					(size 1.27 1.27)
				)
			)
		)
		(property "Value" "R_22R_0402"
			(at 278.13 210.82 0)
			(effects
				(font
					(size 1.27 1.27)
					(thickness 0.15)
				)
				(justify left bottom)
				(hide yes)
			)
		)
		(property "Footprint" "antmicro-footprints:R_0402_1005Metric"
			(at 278.13 213.36 0)
			(effects
				(font
					(size 1.27 1.27)
					(thickness 0.15)
				)
				(justify left bottom)
				(hide yes)
			)
		)
		(property "Datasheet" "https://www.bourns.com/docs/product-datasheets/cr.pdf"
			(at 278.13 215.9 0)
			(effects
				(font
					(size 1.27 1.27)
					(thickness 0.15)
				)
				(justify left bottom)
				(hide yes)
			)
		)
		(property "Description" ""
			(at 257.81 198.12 0)
			(effects
				(font
					(size 1.27 1.27)
				)
			)
		)
		(property "Manufacturer" "Bourns"
			(at 278.13 220.98 0)
			(effects
				(font
					(size 1.27 1.27)
					(thickness 0.15)
				)
				(justify left bottom)
				(hide yes)
			)
		)
		(property "MPN" "CR0402-FX-22R0GLF"
			(at 278.13 218.44 0)
			(effects
				(font
					(size 1.27 1.27)
					(thickness 0.15)
				)
				(justify left bottom)
				(hide yes)
			)
		)
		(property "Val" "22R"
			(at 255.905 196.85 0)
			(effects
				(font
					(size 1.27 1.27)
					(thickness 0.15)
				)
			)
		)
		(property "License" "Apache-2.0"
			(at 278.13 223.52 0)
			(effects
				(font
					(size 1.27 1.27)
					(thickness 0.15)
				)
				(justify left bottom)
				(hide yes)
			)
		)
		(property "Author" "Antmicro"
			(at 278.13 226.06 0)
			(effects
				(font
					(size 1.27 1.27)
					(thickness 0.15)
				)
				(justify left bottom)
				(hide yes)
			)
		)
		(property "Tolerance" "1%"
			(at 278.13 208.28 0)
			(effects
				(font
					(size 1.27 1.27)
				)
				(justify left bottom)
				(hide yes)
			)
		)
		(pin "1"
		)
		(pin "2"
		)
		(instances
			(project "k410t-devboard"
				(path ""
					(reference "R335")
					(unit 1)
				)
			)
		)
	)
	(symbol
		(lib_id "antmicropower:GND")
		(at 200.66 71.12 0)
		(unit 1)
		(exclude_from_sim no)
		(in_bom yes)
		(on_board yes)
		(dnp no)
		(fields_autoplaced yes)
		(property "Reference" "#PWR0468"
			(at 200.66 77.47 0)
			(effects
				(font
					(size 1.27 1.27)
				)
				(hide yes)
			)
		)
		(property "Value" "GND"
			(at 200.66 74.93 0)
			(effects
				(font
					(size 1.27 1.27)
				)
			)
		)
		(property "Footprint" ""
			(at 209.55 78.74 0)
			(effects
				(font
					(size 1.27 1.27)
					(thickness 0.15)
				)
				(justify left bottom)
				(hide yes)
			)
		)
		(property "Datasheet" ""
			(at 209.55 83.82 0)
			(effects
				(font
					(size 1.27 1.27)
					(thickness 0.15)
				)
				(justify left bottom)
				(hide yes)
			)
		)
		(property "Description" ""
			(at 200.66 71.12 0)
			(effects
				(font
					(size 1.27 1.27)
				)
			)
		)
		(property "Author" "Antmicro"
			(at 209.55 78.74 0)
			(effects
				(font
					(size 1.27 1.27)
					(thickness 0.15)
				)
				(justify left bottom)
				(hide yes)
			)
		)
		(property "License" "Apache-2.0"
			(at 209.55 81.28 0)
			(effects
				(font
					(size 1.27 1.27)
					(thickness 0.15)
				)
				(justify left bottom)
				(hide yes)
			)
		)
		(pin "1"
		)
		(instances
			(project "k410t-devboard"
				(path ""
					(reference "#PWR0468")
					(unit 1)
				)
			)
		)
	)
	(symbol
		(lib_id "antmicroFerriteBeadsandChips:FB_120Z_2A_Murata-BLM18PG_0603")
		(at 170.18 176.53 0)
		(mirror y)
		(unit 1)
		(exclude_from_sim no)
		(in_bom yes)
		(on_board yes)
		(dnp no)
		(fields_autoplaced yes)
		(property "Reference" "FB12"
			(at 167.6781 169.545 0)
			(effects
				(font
					(size 1.27 1.27)
				)
			)
		)
		(property "Value" "FB_120Z_2A_Murata-BLM18PG_0603"
			(at 154.94 181.61 0)
			(effects
				(font
					(size 1.27 1.27)
					(thickness 0.15)
				)
				(justify left bottom)
				(hide yes)
			)
		)
		(property "Footprint" "antmicro-footprints:FB_0603_1608Metric"
			(at 154.94 184.15 0)
			(effects
				(font
					(size 1.27 1.27)
					(thickness 0.15)
				)
				(justify left bottom)
				(hide yes)
			)
		)
		(property "Datasheet" "https://www.murata.com/en-us/products/productdata/8796738650142/ENFA0003.pdf"
			(at 154.94 186.69 0)
			(effects
				(font
					(size 1.27 1.27)
					(thickness 0.15)
				)
				(justify left bottom)
				(hide yes)
			)
		)
		(property "Description" ""
			(at 170.18 176.53 0)
			(effects
				(font
					(size 1.27 1.27)
				)
			)
		)
		(property "MPN" "BLM18PG121SN1D"
			(at 167.6781 172.085 0)
			(effects
				(font
					(size 1.27 1.27)
					(thickness 0.15)
				)
			)
		)
		(property "Manufacturer" "Murata"
			(at 154.94 191.77 0)
			(effects
				(font
					(size 1.27 1.27)
					(thickness 0.15)
				)
				(justify left bottom)
				(hide yes)
			)
		)
		(property "Author" "Antmicro"
			(at 154.94 194.31 0)
			(effects
				(font
					(size 1.27 1.27)
					(thickness 0.15)
				)
				(justify left bottom)
				(hide yes)
			)
		)
		(property "License" "Apache-2.0"
			(at 154.94 196.85 0)
			(effects
				(font
					(size 1.27 1.27)
					(thickness 0.15)
				)
				(justify left bottom)
				(hide yes)
			)
		)
		(property "Val" "120Z/2A"
			(at 154.94 181.61 0)
			(effects
				(font
					(size 1.27 1.27)
				)
				(justify left bottom)
			)
		)
		(property "Current" ""
			(at 149.86 199.39 0)
			(effects
				(font
					(size 1.27 1.27)
					(thickness 0.15)
				)
				(justify left bottom)
				(hide yes)
			)
		)
		(pin "1"
		)
		(pin "2"
		)
		(instances
			(project "k410t-devboard"
				(path ""
					(reference "FB12")
					(unit 1)
				)
			)
		)
	)
	(symbol
		(lib_id "antmicroClockTimingClockGeneratorsPLLsFrequencySynthesizers:CDCE906PWR")
		(at 208.28 190.5 0)
		(unit 1)
		(exclude_from_sim no)
		(in_bom yes)
		(on_board yes)
		(dnp no)
		(fields_autoplaced yes)
		(property "Reference" "U42"
			(at 220.98 182.88 0)
			(effects
				(font
					(size 1.27 1.27)
				)
			)
		)
		(property "Value" "CDCE906PWR"
			(at 220.98 185.42 0)
			(effects
				(font
					(size 1.27 1.27)
					(thickness 0.15)
				)
				(hide yes)
			)
		)
		(property "Footprint" "antmicro-footprints:TSSOP-20_W4.4mm"
			(at 246.38 200.66 0)
			(effects
				(font
					(size 1.27 1.27)
					(thickness 0.15)
				)
				(justify left bottom)
				(hide yes)
			)
		)
		(property "Datasheet" "https://www.ti.com/lit/ds/symlink/cdce906.pdf?HQS=dis-mous-null-mousermode-dsf-pf-null-wwe&ts=1672406494449&ref_url=https%253A%252F%252Feu.mouser.com%252F"
			(at 246.38 203.2 0)
			(effects
				(font
					(size 1.27 1.27)
					(thickness 0.15)
				)
				(justify left bottom)
				(hide yes)
			)
		)
		(property "Description" ""
			(at 208.28 190.5 0)
			(effects
				(font
					(size 1.27 1.27)
				)
			)
		)
		(property "MPN" "CDCE906PWR"
			(at 220.98 185.42 0)
			(effects
				(font
					(size 1.27 1.27)
					(thickness 0.15)
				)
			)
		)
		(property "Manufacturer" "Texas Instruments"
			(at 246.38 208.28 0)
			(effects
				(font
					(size 1.27 1.27)
					(thickness 0.15)
				)
				(justify left bottom)
				(hide yes)
			)
		)
		(property "Author" "Antmicro"
			(at 246.38 210.82 0)
			(effects
				(font
					(size 1.27 1.27)
					(thickness 0.15)
				)
				(justify left bottom)
				(hide yes)
			)
		)
		(property "License" "Apache-2.0"
			(at 246.38 213.36 0)
			(effects
				(font
					(size 1.27 1.27)
					(thickness 0.15)
				)
				(justify left bottom)
				(hide yes)
			)
		)
		(pin "1"
		)
		(pin "10"
		)
		(pin "11"
		)
		(pin "12"
		)
		(pin "13"
		)
		(pin "14"
		)
		(pin "15"
		)
		(pin "16"
		)
		(pin "17"
		)
		(pin "18"
		)
		(pin "19"
		)
		(pin "2"
		)
		(pin "20"
		)
		(pin "3"
		)
		(pin "4"
		)
		(pin "5"
		)
		(pin "6"
		)
		(pin "7"
		)
		(pin "8"
		)
		(pin "9"
		)
		(instances
			(project "k410t-devboard"
				(path ""
					(reference "U42")
					(unit 1)
				)
			)
		)
	)
	(symbol
		(lib_id "antmicroCapacitors0402:C_100n_0402")
		(at 198.12 184.15 90)
		(unit 1)
		(exclude_from_sim no)
		(in_bom yes)
		(on_board yes)
		(dnp no)
		(fields_autoplaced yes)
		(property "Reference" "C369"
			(at 200.66 180.3335 90)
			(effects
				(font
					(size 1.27 1.27)
				)
				(justify right)
			)
		)
		(property "Value" "C_100n_0402"
			(at 208.28 163.83 0)
			(effects
				(font
					(size 1.27 1.27)
					(thickness 0.15)
				)
				(justify left bottom)
				(hide yes)
			)
		)
		(property "Footprint" "antmicro-footprints:C_0402_1005Metric"
			(at 210.82 163.83 0)
			(effects
				(font
					(size 1.27 1.27)
					(thickness 0.15)
				)
				(justify left bottom)
				(hide yes)
			)
		)
		(property "Datasheet" "https://www.murata.com/products/productdetail?partno=GRM155R61H104KE14%23"
			(at 213.36 163.83 0)
			(effects
				(font
					(size 1.27 1.27)
					(thickness 0.15)
				)
				(justify left bottom)
				(hide yes)
			)
		)
		(property "Description" ""
			(at 198.12 184.15 0)
			(effects
				(font
					(size 1.27 1.27)
				)
			)
		)
		(property "Manufacturer" "Murata"
			(at 218.44 163.83 0)
			(effects
				(font
					(size 1.27 1.27)
					(thickness 0.15)
				)
				(justify left bottom)
				(hide yes)
			)
		)
		(property "MPN" "GRM155R61H104KE14D"
			(at 215.9 163.83 0)
			(effects
				(font
					(size 1.27 1.27)
					(thickness 0.15)
				)
				(justify left bottom)
				(hide yes)
			)
		)
		(property "Val" "100n"
			(at 200.66 182.8735 90)
			(effects
				(font
					(size 1.27 1.27)
					(thickness 0.15)
				)
				(justify right)
			)
		)
		(property "License" "Apache-2.0"
			(at 220.98 163.83 0)
			(effects
				(font
					(size 1.27 1.27)
					(thickness 0.15)
				)
				(justify left bottom)
				(hide yes)
			)
		)
		(property "Author" "Antmicro"
			(at 223.52 163.83 0)
			(effects
				(font
					(size 1.27 1.27)
					(thickness 0.15)
				)
				(justify left bottom)
				(hide yes)
			)
		)
		(property "Voltage" "50V"
			(at 226.06 163.83 0)
			(effects
				(font
					(size 1.27 1.27)
				)
				(justify left bottom)
				(hide yes)
			)
		)
		(property "Dielectric" "X5R"
			(at 228.6 163.83 0)
			(effects
				(font
					(size 1.27 1.27)
				)
				(justify left bottom)
				(hide yes)
			)
		)
		(pin "1"
		)
		(pin "2"
		)
		(instances
			(project "k410t-devboard"
				(path ""
					(reference "C369")
					(unit 1)
				)
			)
		)
	)
	(symbol
		(lib_id "antmicropower:GND")
		(at 209.55 90.17 0)
		(unit 1)
		(exclude_from_sim no)
		(in_bom yes)
		(on_board yes)
		(dnp no)
		(fields_autoplaced yes)
		(property "Reference" "#PWR0469"
			(at 209.55 96.52 0)
			(effects
				(font
					(size 1.27 1.27)
				)
				(hide yes)
			)
		)
		(property "Value" "GND"
			(at 209.55 93.98 0)
			(effects
				(font
					(size 1.27 1.27)
				)
			)
		)
		(property "Footprint" ""
			(at 218.44 97.79 0)
			(effects
				(font
					(size 1.27 1.27)
					(thickness 0.15)
				)
				(justify left bottom)
				(hide yes)
			)
		)
		(property "Datasheet" ""
			(at 218.44 102.87 0)
			(effects
				(font
					(size 1.27 1.27)
					(thickness 0.15)
				)
				(justify left bottom)
				(hide yes)
			)
		)
		(property "Description" ""
			(at 209.55 90.17 0)
			(effects
				(font
					(size 1.27 1.27)
				)
			)
		)
		(property "Author" "Antmicro"
			(at 218.44 97.79 0)
			(effects
				(font
					(size 1.27 1.27)
					(thickness 0.15)
				)
				(justify left bottom)
				(hide yes)
			)
		)
		(property "License" "Apache-2.0"
			(at 218.44 100.33 0)
			(effects
				(font
					(size 1.27 1.27)
					(thickness 0.15)
				)
				(justify left bottom)
				(hide yes)
			)
		)
		(pin "1"
		)
		(instances
			(project "k410t-devboard"
				(path ""
					(reference "#PWR0469")
					(unit 1)
				)
			)
		)
	)
	(symbol
		(lib_id "antmicroCapacitors0402:C_100n_0402")
		(at 243.84 179.07 90)
		(mirror x)
		(unit 1)
		(exclude_from_sim no)
		(in_bom yes)
		(on_board yes)
		(dnp no)
		(property "Reference" "C371"
			(at 244.475 179.705 90)
			(effects
				(font
					(size 1.27 1.27)
				)
				(justify right)
			)
		)
		(property "Value" "C_100n_0402"
			(at 254 199.39 0)
			(effects
				(font
					(size 1.27 1.27)
					(thickness 0.15)
				)
				(justify left bottom)
				(hide yes)
			)
		)
		(property "Footprint" "antmicro-footprints:C_0402_1005Metric"
			(at 256.54 199.39 0)
			(effects
				(font
					(size 1.27 1.27)
					(thickness 0.15)
				)
				(justify left bottom)
				(hide yes)
			)
		)
		(property "Datasheet" "https://www.murata.com/products/productdetail?partno=GRM155R61H104KE14%23"
			(at 259.08 199.39 0)
			(effects
				(font
					(size 1.27 1.27)
					(thickness 0.15)
				)
				(justify left bottom)
				(hide yes)
			)
		)
		(property "Description" ""
			(at 243.84 179.07 0)
			(effects
				(font
					(size 1.27 1.27)
				)
			)
		)
		(property "Manufacturer" "Murata"
			(at 264.16 199.39 0)
			(effects
				(font
					(size 1.27 1.27)
					(thickness 0.15)
				)
				(justify left bottom)
				(hide yes)
			)
		)
		(property "MPN" "GRM155R61H104KE14D"
			(at 261.62 199.39 0)
			(effects
				(font
					(size 1.27 1.27)
					(thickness 0.15)
				)
				(justify left bottom)
				(hide yes)
			)
		)
		(property "Val" "100n"
			(at 244.475 183.515 90)
			(effects
				(font
					(size 1.27 1.27)
					(thickness 0.15)
				)
				(justify right)
			)
		)
		(property "License" "Apache-2.0"
			(at 266.7 199.39 0)
			(effects
				(font
					(size 1.27 1.27)
					(thickness 0.15)
				)
				(justify left bottom)
				(hide yes)
			)
		)
		(property "Author" "Antmicro"
			(at 269.24 199.39 0)
			(effects
				(font
					(size 1.27 1.27)
					(thickness 0.15)
				)
				(justify left bottom)
				(hide yes)
			)
		)
		(property "Voltage" "50V"
			(at 271.78 199.39 0)
			(effects
				(font
					(size 1.27 1.27)
				)
				(justify left bottom)
				(hide yes)
			)
		)
		(property "Dielectric" "X5R"
			(at 274.32 199.39 0)
			(effects
				(font
					(size 1.27 1.27)
				)
				(justify left bottom)
				(hide yes)
			)
		)
		(pin "1"
		)
		(pin "2"
		)
		(instances
			(project "k410t-devboard"
				(path ""
					(reference "C371")
					(unit 1)
				)
			)
		)
	)
	(symbol
		(lib_id "antmicroCapacitors0402:C_100n_0402")
		(at 200.66 68.58 90)
		(unit 1)
		(exclude_from_sim no)
		(in_bom yes)
		(on_board yes)
		(dnp no)
		(fields_autoplaced yes)
		(property "Reference" "C370"
			(at 203.2 64.7635 90)
			(effects
				(font
					(size 1.27 1.27)
				)
				(justify right)
			)
		)
		(property "Value" "C_100n_0402"
			(at 210.82 48.26 0)
			(effects
				(font
					(size 1.27 1.27)
					(thickness 0.15)
				)
				(justify left bottom)
				(hide yes)
			)
		)
		(property "Footprint" "antmicro-footprints:C_0402_1005Metric"
			(at 213.36 48.26 0)
			(effects
				(font
					(size 1.27 1.27)
					(thickness 0.15)
				)
				(justify left bottom)
				(hide yes)
			)
		)
		(property "Datasheet" "https://www.murata.com/products/productdetail?partno=GRM155R61H104KE14%23"
			(at 215.9 48.26 0)
			(effects
				(font
					(size 1.27 1.27)
					(thickness 0.15)
				)
				(justify left bottom)
				(hide yes)
			)
		)
		(property "Description" ""
			(at 200.66 68.58 0)
			(effects
				(font
					(size 1.27 1.27)
				)
			)
		)
		(property "Manufacturer" "Murata"
			(at 220.98 48.26 0)
			(effects
				(font
					(size 1.27 1.27)
					(thickness 0.15)
				)
				(justify left bottom)
				(hide yes)
			)
		)
		(property "MPN" "GRM155R61H104KE14D"
			(at 218.44 48.26 0)
			(effects
				(font
					(size 1.27 1.27)
					(thickness 0.15)
				)
				(justify left bottom)
				(hide yes)
			)
		)
		(property "Val" "100n"
			(at 203.2 67.3035 90)
			(effects
				(font
					(size 1.27 1.27)
					(thickness 0.15)
				)
				(justify right)
			)
		)
		(property "License" "Apache-2.0"
			(at 223.52 48.26 0)
			(effects
				(font
					(size 1.27 1.27)
					(thickness 0.15)
				)
				(justify left bottom)
				(hide yes)
			)
		)
		(property "Author" "Antmicro"
			(at 226.06 48.26 0)
			(effects
				(font
					(size 1.27 1.27)
					(thickness 0.15)
				)
				(justify left bottom)
				(hide yes)
			)
		)
		(property "Voltage" "50V"
			(at 228.6 48.26 0)
			(effects
				(font
					(size 1.27 1.27)
				)
				(justify left bottom)
				(hide yes)
			)
		)
		(property "Dielectric" "X5R"
			(at 231.14 48.26 0)
			(effects
				(font
					(size 1.27 1.27)
				)
				(justify left bottom)
				(hide yes)
			)
		)
		(pin "1"
		)
		(pin "2"
		)
		(instances
			(project "k410t-devboard"
				(path ""
					(reference "C370")
					(unit 1)
				)
			)
		)
	)
)
